(kicad_pcb
	(version 20260206)
	(generator "pcbnew")
	(generator_version "10.0")
	(general
		(thickness 1.6)
		(legacy_teardrops no)
	)
	(paper "A4")
	(title_block
		(title "Wiwynn_Tioga_Pass_MB.brd")
		(comment 1 "Tioga Pass / footprints 808-814 of 4770")
	)
	(layers
		(0 "F.Cu" signal "TOP")
		(4 "In1.Cu" signal "L2GND")
		(6 "In2.Cu" signal "L3")
		(8 "In3.Cu" signal "L4GND")
		(10 "In4.Cu" signal "L5")
		(12 "In5.Cu" signal "L6GND")
		(14 "In6.Cu" signal "L7VCC")
		(16 "In7.Cu" signal "L8VCC")
		(18 "In8.Cu" signal "L9GND")
		(20 "In9.Cu" signal "L10")
		(22 "In10.Cu" signal "L11GND")
		(24 "In11.Cu" signal "L12")
		(26 "In12.Cu" signal "L13GND")
		(2 "B.Cu" signal "BOTTOM")
		(9 "F.Adhes" user "F.Adhesive")
		(11 "B.Adhes" user "B.Adhesive")
		(13 "F.Paste" user "Package Geometry/Pastemask Top")
		(15 "B.Paste" user "Package Geometry/Pastemask Bottom")
		(5 "F.SilkS" user "Ref Des/Silkscreen Top")
		(7 "B.SilkS" user "Ref Des/Silkscreen Bottom")
		(1 "F.Mask" user "Board Geometry/Soldermask Top")
		(3 "B.Mask" user "Board Geometry/Soldermask Bottom")
		(17 "Dwgs.User" user "User.Drawings")
		(19 "Cmts.User" user "User.Comments")
		(21 "Eco1.User" user "User.Eco1")
		(23 "Eco2.User" user "User.Eco2")
		(25 "Edge.Cuts" user "Board Geometry/Outline")
		(27 "Margin" user)
		(31 "F.CrtYd" user "Package Geometry/Place Bound Top")
		(29 "B.CrtYd" user "Package Geometry/Place Bound Bottom")
		(35 "F.Fab" user "Ref Des/Assembly Top")
		(33 "B.Fab" user "Ref Des/Assembly Bottom")
	)
	(footprint ""
		(layer "F.Cu")
		(at 28.829 -66.929 90)
		(property "Reference" "C1D36"
			(at 0 0 90)
			(layer "F.SilkS")
			(hide yes)
			(effects
				(font
					(size 1.27 1.27)
				)
			)
		)
		(property "Value" ""
			(at 0 0 90)
			(layer "F.Fab")
			(effects
				(font
					(size 1.27 1.27)
				)
			)
		)
		(duplicate_pad_numbers_are_jumpers no)
		(fp_rect
			(start -0.3048 0.9906)
			(end 0.3048 -0.1016)
			(stroke
				(width 0)
				(type default)
			)
			(fill no)
			(layer "F.CrtYd")
		)
		(fp_line
			(start 0.3048 -0.1016)
			(end -0.3048 -0.1016)
			(stroke
				(width 0.1)
				(type default)
			)
			(layer "F.Fab")
		)
		(fp_line
			(start -0.3048 -0.1016)
			(end -0.3048 0.9906)
			(stroke
				(width 0.1)
				(type default)
			)
			(layer "F.Fab")
		)
		(fp_line
			(start 0.3048 0.9906)
			(end 0.3048 -0.1016)
			(stroke
				(width 0.1)
				(type default)
			)
			(layer "F.Fab")
		)
		(fp_line
			(start -0.3048 0.9906)
			(end 0.3048 0.9906)
			(stroke
				(width 0.1)
				(type default)
			)
			(layer "F.Fab")
		)
		(pad "1" smd rect
			(at 0 0 90)
			(size 0.508 0.508)
			(layers "F.Cu" "F.Mask" "F.Paste")
			(net "VR_PVCCIN_CPU1_PH2_BOOT")
		)
		(pad "2" smd rect
			(at 0 0.889 90)
			(size 0.508 0.508)
			(layers "F.Cu" "F.Mask" "F.Paste")
			(net "VR_PVCCIN_CPU1_PH2_PHASE")
		)
		(zone
			(layer "F.Cu")
			(hatch none 0.5)
			(connect_pads
				(clearance 0)
			)
			(min_thickness 0.25)
			(keepout
				(tracks allowed)
				(vias not_allowed)
				(pads allowed)
				(copperpour not_allowed)
				(footprints allowed)
			)
			(placement
				(enabled no)
				(sheetname "")
			)
			(fill
				(thermal_gap 0.5)
				(thermal_bridge_width 0.5)
				(island_removal_mode 0)
			)
			(polygon
				(pts
					(xy 29.464 -66.675) (xy 29.464 -67.183) (xy 29.083 -67.183) (xy 29.083 -66.675)
				)
			)
		)
		(zone
			(layer "F.Cu")
			(hatch none 0.5)
			(connect_pads
				(clearance 0)
			)
			(min_thickness 0.25)
			(keepout
				(tracks not_allowed)
				(vias allowed)
				(pads allowed)
				(copperpour not_allowed)
				(footprints allowed)
			)
			(placement
				(enabled no)
				(sheetname "")
			)
			(fill
				(thermal_gap 0.5)
				(thermal_bridge_width 0.5)
				(island_removal_mode 0)
			)
			(polygon
				(pts
					(xy 29.464 -66.675) (xy 29.464 -67.183) (xy 29.083 -67.183) (xy 29.083 -66.675)
				)
			)
		)
	)
	(footprint ""
		(layer "F.Cu")
		(at 20.701 -32.258)
		(property "Reference" "CR1F3"
			(at -3.429 -1.24333 0)
			(unlocked yes)
			(layer "F.SilkS")
			(effects
				(font
					(size 0.7874 0.5842)
					(thickness 0.1524)
				)
				(justify left)
			)
		)
		(property "Value" ""
			(at 0 0 0)
			(layer "F.Fab")
			(effects
				(font
					(size 1.27 1.27)
				)
			)
		)
		(duplicate_pad_numbers_are_jumpers no)
		(fp_line
			(start -1.8161 1.664462)
			(end -1.335278 0.831596)
			(stroke
				(width 0.1524)
				(type default)
			)
			(layer "F.SilkS")
		)
		(fp_line
			(start -1.335278 -0.291846)
			(end -1.335278 0.831596)
			(stroke
				(width 0.1524)
				(type default)
			)
			(layer "F.SilkS")
		)
		(fp_line
			(start -1.335278 0.831596)
			(end -0.854456 1.664462)
			(stroke
				(width 0.1524)
				(type default)
			)
			(layer "F.SilkS")
		)
		(fp_line
			(start -1.335278 1.664462)
			(end -1.8161 1.664462)
			(stroke
				(width 0.1524)
				(type default)
			)
			(layer "F.SilkS")
		)
		(fp_line
			(start -1.335278 2.576068)
			(end -1.335278 1.664462)
			(stroke
				(width 0.1524)
				(type default)
			)
			(layer "F.SilkS")
		)
		(fp_line
			(start -0.854456 0.831596)
			(end -1.8161 0.831596)
			(stroke
				(width 0.1524)
				(type default)
			)
			(layer "F.SilkS")
		)
		(fp_line
			(start -0.854456 1.664462)
			(end -1.335278 1.664462)
			(stroke
				(width 0.1524)
				(type default)
			)
			(layer "F.SilkS")
		)
		(fp_rect
			(start -0.67437 2.04216)
			(end 0.67437 0.24384)
			(stroke
				(width 0)
				(type default)
			)
			(fill no)
			(layer "F.CrtYd")
		)
		(fp_line
			(start -1.8161 1.664462)
			(end -1.335278 0.831596)
			(stroke
				(width 0.1)
				(type default)
			)
			(layer "F.Fab")
		)
		(fp_line
			(start -1.335278 0.831596)
			(end -1.335278 -0.291846)
			(stroke
				(width 0.1)
				(type default)
			)
			(layer "F.Fab")
		)
		(fp_line
			(start -1.335278 0.831596)
			(end -0.854456 1.664462)
			(stroke
				(width 0.1)
				(type default)
			)
			(layer "F.Fab")
		)
		(fp_line
			(start -1.335278 1.664462)
			(end -1.335278 2.576068)
			(stroke
				(width 0.1)
				(type default)
			)
			(layer "F.Fab")
		)
		(fp_line
			(start -0.854456 0.831596)
			(end -1.8161 0.831596)
			(stroke
				(width 0.1)
				(type default)
			)
			(layer "F.Fab")
		)
		(fp_line
			(start -0.854456 1.664462)
			(end -1.8161 1.664462)
			(stroke
				(width 0.1)
				(type default)
			)
			(layer "F.Fab")
		)
		(fp_line
			(start -0.67437 0.24384)
			(end -0.67437 2.04216)
			(stroke
				(width 0.1)
				(type default)
			)
			(layer "F.Fab")
		)
		(fp_line
			(start -0.67437 2.04216)
			(end 0.67437 2.04216)
			(stroke
				(width 0.1)
				(type default)
			)
			(layer "F.Fab")
		)
		(fp_line
			(start 0.67437 0.24384)
			(end -0.67437 0.24384)
			(stroke
				(width 0.1)
				(type default)
			)
			(layer "F.Fab")
		)
		(fp_line
			(start 0.67437 2.04216)
			(end 0.67437 0.24384)
			(stroke
				(width 0.1)
				(type default)
			)
			(layer "F.Fab")
		)
		(pad "1" smd rect
			(at 0 0)
			(size 0.4064 1.016)
			(layers "F.Cu" "F.Mask" "F.Paste")
			(net "FM_MATED_IN_D2_N")
		)
		(pad "2" smd rect
			(at 0 2.286)
			(size 0.4064 1.016)
			(layers "F.Cu" "F.Mask" "F.Paste")
			(net "FM_MATED_IN_D1_N")
		)
	)
	(footprint ""
		(layer "F.Cu")
		(at 324.5485 -123.825 90)
		(property "Reference" "C6B6"
			(at -0.8382 -0.67818 90)
			(unlocked yes)
			(layer "F.SilkS")
			(effects
				(font
					(size 0.4064 0.254)
					(thickness 0.1524)
				)
				(justify left)
			)
		)
		(property "Value" ""
			(at 0 0 90)
			(layer "F.Fab")
			(effects
				(font
					(size 1.27 1.27)
				)
			)
		)
		(duplicate_pad_numbers_are_jumpers no)
		(fp_poly
			(pts
				(xy 0.3048 -0.1016) (xy 0.3048 0.9906) (xy -0.3048 0.9906) (xy -0.3048 -0.1016)
			)
			(stroke
				(width 0)
				(type default)
			)
			(fill no)
			(layer "F.CrtYd")
		)
		(fp_line
			(start 0.3048 -0.1016)
			(end -0.3048 -0.1016)
			(stroke
				(width 0.1)
				(type default)
			)
			(layer "F.Fab")
		)
		(fp_line
			(start -0.3048 -0.1016)
			(end -0.3048 0.9906)
			(stroke
				(width 0.1)
				(type default)
			)
			(layer "F.Fab")
		)
		(fp_line
			(start 0.3048 0.9906)
			(end 0.3048 -0.1016)
			(stroke
				(width 0.1)
				(type default)
			)
			(layer "F.Fab")
		)
		(fp_line
			(start -0.3048 0.9906)
			(end 0.3048 0.9906)
			(stroke
				(width 0.1)
				(type default)
			)
			(layer "F.Fab")
		)
		(pad "1" smd rect
			(at 0 0 90)
			(size 0.508 0.508)
			(layers "F.Cu" "F.Mask" "F.Paste")
			(net "P3E_CPU0_PE1_PCH_TXN<14>")
		)
		(pad "2" smd rect
			(at 0 0.889 90)
			(size 0.508 0.508)
			(layers "F.Cu" "F.Mask" "F.Paste")
			(net "P3E_CPU0_PE1_PCH_C_TXN<14>")
		)
		(zone
			(layer "F.Cu")
			(hatch none 0.5)
			(connect_pads
				(clearance 0)
			)
			(min_thickness 0.25)
			(keepout
				(tracks allowed)
				(vias not_allowed)
				(pads allowed)
				(copperpour not_allowed)
				(footprints allowed)
			)
			(placement
				(enabled no)
				(sheetname "")
			)
			(fill
				(thermal_gap 0.5)
				(thermal_bridge_width 0.5)
				(island_removal_mode 0)
			)
			(polygon
				(pts
					(xy 324.8025 -123.571) (xy 324.8025 -124.079) (xy 325.1835 -124.079) (xy 325.1835 -123.571)
				)
			)
		)
		(zone
			(layer "F.Cu")
			(hatch none 0.5)
			(connect_pads
				(clearance 0)
			)
			(min_thickness 0.25)
			(keepout
				(tracks not_allowed)
				(vias allowed)
				(pads allowed)
				(copperpour not_allowed)
				(footprints allowed)
			)
			(placement
				(enabled no)
				(sheetname "")
			)
			(fill
				(thermal_gap 0.5)
				(thermal_bridge_width 0.5)
				(island_removal_mode 0)
			)
			(polygon
				(pts
					(xy 325.1835 -123.571) (xy 325.1835 -124.079) (xy 324.8025 -124.079) (xy 324.8025 -123.571)
				)
			)
		)
	)
	(footprint ""
		(layer "F.Cu")
		(at 491.423706 -151.39416 -90)
		(property "Reference" "R6W19"
			(at -0.8382 -0.67818 270)
			(unlocked yes)
			(layer "F.SilkS")
			(effects
				(font
					(size 0.4064 0.254)
					(thickness 0.1524)
				)
				(justify left)
			)
		)
		(property "Value" ""
			(at 0 0 270)
			(layer "F.Fab")
			(effects
				(font
					(size 1.27 1.27)
				)
			)
		)
		(duplicate_pad_numbers_are_jumpers no)
		(fp_poly
			(pts
				(xy -0.2794 -0.1016) (xy 0.2794 -0.1016) (xy 0.2794 0.9906) (xy -0.2794 0.9906)
			)
			(stroke
				(width 0)
				(type default)
			)
			(fill no)
			(layer "F.CrtYd")
		)
		(fp_line
			(start -0.2794 0.9906)
			(end 0.2794 0.9906)
			(stroke
				(width 0.1)
				(type default)
			)
			(layer "F.Fab")
		)
		(fp_line
			(start 0.2794 0.9906)
			(end 0.2794 -0.1016)
			(stroke
				(width 0.1)
				(type default)
			)
			(layer "F.Fab")
		)
		(fp_line
			(start -0.2794 -0.1016)
			(end -0.2794 0.9906)
			(stroke
				(width 0.1)
				(type default)
			)
			(layer "F.Fab")
		)
		(fp_line
			(start 0.2794 -0.1016)
			(end -0.2794 -0.1016)
			(stroke
				(width 0.1)
				(type default)
			)
			(layer "F.Fab")
		)
		(pad "1" smd rect
			(at 0 0 270)
			(size 0.508 0.508)
			(layers "F.Cu" "F.Mask" "F.Paste")
			(net "SPA_5V_SIN_SW_D")
		)
		(pad "2" smd rect
			(at 0 0.889 270)
			(size 0.508 0.508)
			(layers "F.Cu" "F.Mask" "F.Paste")
			(net "SPA_SIN_SW_R")
		)
		(zone
			(layer "F.Cu")
			(hatch none 0.5)
			(connect_pads
				(clearance 0)
			)
			(min_thickness 0.25)
			(keepout
				(tracks not_allowed)
				(vias allowed)
				(pads allowed)
				(copperpour not_allowed)
				(footprints allowed)
			)
			(placement
				(enabled no)
				(sheetname "")
			)
			(fill
				(thermal_gap 0.5)
				(thermal_bridge_width 0.5)
				(island_removal_mode 0)
			)
			(polygon
				(pts
					(xy 490.788706 -151.64816) (xy 490.788706 -151.14016) (xy 491.169706 -151.14016) (xy 491.169706 -151.64816)
				)
			)
		)
		(zone
			(layer "F.Cu")
			(hatch none 0.5)
			(connect_pads
				(clearance 0)
			)
			(min_thickness 0.25)
			(keepout
				(tracks allowed)
				(vias not_allowed)
				(pads allowed)
				(copperpour not_allowed)
				(footprints allowed)
			)
			(placement
				(enabled no)
				(sheetname "")
			)
			(fill
				(thermal_gap 0.5)
				(thermal_bridge_width 0.5)
				(island_removal_mode 0)
			)
			(polygon
				(pts
					(xy 491.169706 -151.64816) (xy 491.169706 -151.14016) (xy 490.788706 -151.14016) (xy 490.788706 -151.64816)
				)
			)
		)
	)
	(footprint ""
		(layer "F.Cu")
		(at 407.8605 -108.966 90)
		(property "Reference" "R8C11"
			(at 0 0 90)
			(layer "F.SilkS")
			(hide yes)
			(effects
				(font
					(size 1.27 1.27)
				)
			)
		)
		(property "Value" ""
			(at 0 0 90)
			(layer "F.Fab")
			(effects
				(font
					(size 1.27 1.27)
				)
			)
		)
		(duplicate_pad_numbers_are_jumpers no)
		(fp_poly
			(pts
				(xy -0.2794 -0.1016) (xy 0.2794 -0.1016) (xy 0.2794 0.9906) (xy -0.2794 0.9906)
			)
			(stroke
				(width 0)
				(type default)
			)
			(fill no)
			(layer "F.CrtYd")
		)
		(fp_line
			(start 0.2794 -0.1016)
			(end -0.2794 -0.1016)
			(stroke
				(width 0.1)
				(type default)
			)
			(layer "F.Fab")
		)
		(fp_line
			(start -0.2794 -0.1016)
			(end -0.2794 0.9906)
			(stroke
				(width 0.1)
				(type default)
			)
			(layer "F.Fab")
		)
		(fp_line
			(start 0.2794 0.9906)
			(end 0.2794 -0.1016)
			(stroke
				(width 0.1)
				(type default)
			)
			(layer "F.Fab")
		)
		(fp_line
			(start -0.2794 0.9906)
			(end 0.2794 0.9906)
			(stroke
				(width 0.1)
				(type default)
			)
			(layer "F.Fab")
		)
		(pad "1" smd rect
			(at 0 0 90)
			(size 0.508 0.508)
			(layers "F.Cu" "F.Mask" "F.Paste")
			(net "SMB_SMLINK0_STBY_LVC3_SDA_R1")
		)
		(pad "2" smd rect
			(at 0 0.889 90)
			(size 0.508 0.508)
			(layers "F.Cu" "F.Mask" "F.Paste")
			(net "SMB_SMLINK0_STBY_LVC3_SDA")
		)
		(zone
			(layer "F.Cu")
			(hatch none 0.5)
			(connect_pads
				(clearance 0)
			)
			(min_thickness 0.25)
			(keepout
				(tracks allowed)
				(vias not_allowed)
				(pads allowed)
				(copperpour not_allowed)
				(footprints allowed)
			)
			(placement
				(enabled no)
				(sheetname "")
			)
			(fill
				(thermal_gap 0.5)
				(thermal_bridge_width 0.5)
				(island_removal_mode 0)
			)
			(polygon
				(pts
					(xy 408.1145 -108.712) (xy 408.1145 -109.22) (xy 408.4955 -109.22) (xy 408.4955 -108.712)
				)
			)
		)
		(zone
			(layer "F.Cu")
			(hatch none 0.5)
			(connect_pads
				(clearance 0)
			)
			(min_thickness 0.25)
			(keepout
				(tracks not_allowed)
				(vias allowed)
				(pads allowed)
				(copperpour not_allowed)
				(footprints allowed)
			)
			(placement
				(enabled no)
				(sheetname "")
			)
			(fill
				(thermal_gap 0.5)
				(thermal_bridge_width 0.5)
				(island_removal_mode 0)
			)
			(polygon
				(pts
					(xy 408.4955 -108.712) (xy 408.4955 -109.22) (xy 408.1145 -109.22) (xy 408.1145 -108.712)
				)
			)
		)
	)
	(footprint ""
		(layer "F.Cu")
		(at -4.3688 -131.2672)
		(property "Reference" "R1B13"
			(at -0.8382 -0.67818 0)
			(unlocked yes)
			(layer "F.SilkS")
			(effects
				(font
					(size 0.4064 0.254)
					(thickness 0.1524)
				)
				(justify left)
			)
		)
		(property "Value" ""
			(at 0 0 0)
			(layer "F.Fab")
			(effects
				(font
					(size 1.27 1.27)
				)
			)
		)
		(duplicate_pad_numbers_are_jumpers no)
		(fp_poly
			(pts
				(xy -0.2794 -0.1016) (xy 0.2794 -0.1016) (xy 0.2794 0.9906) (xy -0.2794 0.9906)
			)
			(stroke
				(width 0)
				(type default)
			)
			(fill no)
			(layer "F.CrtYd")
		)
		(fp_line
			(start -0.2794 -0.1016)
			(end -0.2794 0.9906)
			(stroke
				(width 0.1)
				(type default)
			)
			(layer "F.Fab")
		)
		(fp_line
			(start -0.2794 0.9906)
			(end 0.2794 0.9906)
			(stroke
				(width 0.1)
				(type default)
			)
			(layer "F.Fab")
		)
		(fp_line
			(start 0.2794 -0.1016)
			(end -0.2794 -0.1016)
			(stroke
				(width 0.1)
				(type default)
			)
			(layer "F.Fab")
		)
		(fp_line
			(start 0.2794 0.9906)
			(end 0.2794 -0.1016)
			(stroke
				(width 0.1)
				(type default)
			)
			(layer "F.Fab")
		)
		(pad "1" smd rect
			(at 0 0)
			(size 0.508 0.508)
			(layers "F.Cu" "F.Mask" "F.Paste")
			(net "P3V3_STBY")
		)
		(pad "2" smd rect
			(at 0 0.889)
			(size 0.508 0.508)
			(layers "F.Cu" "F.Mask" "F.Paste")
			(net "PWRGD_PVDDQ_KLM")
		)
		(zone
			(layer "F.Cu")
			(hatch none 0.5)
			(connect_pads
				(clearance 0)
			)
			(min_thickness 0.25)
			(keepout
				(tracks allowed)
				(vias not_allowed)
				(pads allowed)
				(copperpour not_allowed)
				(footprints allowed)
			)
			(placement
				(enabled no)
				(sheetname "")
			)
			(fill
				(thermal_gap 0.5)
				(thermal_bridge_width 0.5)
				(island_removal_mode 0)
			)
			(polygon
				(pts
					(xy -4.6228 -131.0132) (xy -4.1148 -131.0132) (xy -4.1148 -130.6322) (xy -4.6228 -130.6322)
				)
			)
		)
		(zone
			(layer "F.Cu")
			(hatch none 0.5)
			(connect_pads
				(clearance 0)
			)
			(min_thickness 0.25)
			(keepout
				(tracks not_allowed)
				(vias allowed)
				(pads allowed)
				(copperpour not_allowed)
				(footprints allowed)
			)
			(placement
				(enabled no)
				(sheetname "")
			)
			(fill
				(thermal_gap 0.5)
				(thermal_bridge_width 0.5)
				(island_removal_mode 0)
			)
			(polygon
				(pts
					(xy -4.6228 -130.6322) (xy -4.1148 -130.6322) (xy -4.1148 -131.0132) (xy -4.6228 -131.0132)
				)
			)
		)
	)
	(footprint ""
		(layer "F.Cu")
		(at 4.2164 -5.675376 90)
		(property "Reference" "C1G5"
			(at 0 0 90)
			(layer "F.SilkS")
			(hide yes)
			(effects
				(font
					(size 1.27 1.27)
				)
			)
		)
		(property "Value" ""
			(at 0 0 90)
			(layer "F.Fab")
			(effects
				(font
					(size 1.27 1.27)
				)
			)
		)
		(duplicate_pad_numbers_are_jumpers no)
		(fp_rect
			(start 0.3048 0.9906)
			(end -0.3048 -0.1016)
			(stroke
				(width 0)
				(type default)
			)
			(fill no)
			(layer "F.CrtYd")
		)
		(fp_line
			(start 0.3048 -0.1016)
			(end -0.3048 -0.1016)
			(stroke
				(width 0.1)
				(type default)
			)
			(layer "F.Fab")
		)
		(fp_line
			(start -0.3048 -0.1016)
			(end -0.3048 0.9906)
			(stroke
				(width 0.1)
				(type default)
			)
			(layer "F.Fab")
		)
		(fp_line
			(start 0.3048 0.9906)
			(end 0.3048 -0.1016)
			(stroke
				(width 0.1)
				(type default)
			)
			(layer "F.Fab")
		)
		(fp_line
			(start -0.3048 0.9906)
			(end 0.3048 0.9906)
			(stroke
				(width 0.1)
				(type default)
			)
			(layer "F.Fab")
		)
		(pad "1" smd rect
			(at 0 0 90)
			(size 0.508 0.508)
			(layers "F.Cu" "F.Mask" "F.Paste")
			(net "P5V_STBY")
		)
		(pad "2" smd rect
			(at 0 0.889 90)
			(size 0.508 0.508)
			(layers "F.Cu" "F.Mask" "F.Paste")
			(net "GND")
		)
		(zone
			(layer "F.Cu")
			(hatch none 0.5)
			(connect_pads
				(clearance 0)
			)
			(min_thickness 0.25)
			(keepout
				(tracks not_allowed)
				(vias allowed)
				(pads allowed)
				(copperpour not_allowed)
				(footprints allowed)
			)
			(placement
				(enabled no)
				(sheetname "")
			)
			(fill
				(thermal_gap 0.5)
				(thermal_bridge_width 0.5)
				(island_removal_mode 0)
			)
			(polygon
				(pts
					(xy 4.8514 -5.929376) (xy 4.4704 -5.929376) (xy 4.4704 -5.421376) (xy 4.8514 -5.421376)
				)
			)
		)
		(zone
			(layer "F.Cu")
			(hatch none 0.5)
			(connect_pads
				(clearance 0)
			)
			(min_thickness 0.25)
			(keepout
				(tracks allowed)
				(vias not_allowed)
				(pads allowed)
				(copperpour not_allowed)
				(footprints allowed)
			)
			(placement
				(enabled no)
				(sheetname "")
			)
			(fill
				(thermal_gap 0.5)
				(thermal_bridge_width 0.5)
				(island_removal_mode 0)
			)
			(polygon
				(pts
					(xy 4.8514 -5.929376) (xy 4.4704 -5.929376) (xy 4.4704 -5.421376) (xy 4.8514 -5.421376)
				)
			)
		)
	)
)
